(kicad_pcb
	(version 20241229)
	(generator "pcbnew")
	(generator_version "9.0")
	(general
		(thickness 1.62)
		(legacy_teardrops no)
	)
	(paper "A3")
	(title_block
		(title "COM Express 7 Baseboard")
		(date "2025-02-04")
		(rev "1.1.2")
		(company "Antmicro Ltd")
		(comment 1 "www.antmicro.com")
		(comment 9 "footprints 611-616 of 802")
	)
	(layers
		(0 "F.Cu" signal)
		(4 "In1.Cu" signal)
		(6 "In2.Cu" signal)
		(8 "In3.Cu" signal)
		(10 "In4.Cu" signal)
		(12 "In5.Cu" signal)
		(14 "In6.Cu" signal)
		(2 "B.Cu" signal)
		(9 "F.Adhes" user "F.Adhesive")
		(11 "B.Adhes" user "B.Adhesive")
		(13 "F.Paste" user)
		(15 "B.Paste" user)
		(5 "F.SilkS" user "F.Silkscreen")
		(7 "B.SilkS" user "B.Silkscreen")
		(1 "F.Mask" user)
		(3 "B.Mask" user)
		(17 "Dwgs.User" user "User.Drawings")
		(19 "Cmts.User" user "User.Comments")
		(21 "Eco1.User" user "User.Eco1")
		(23 "Eco2.User" user "User.Eco2")
		(25 "Edge.Cuts" user)
		(27 "Margin" user)
		(31 "F.CrtYd" user "F.Courtyard")
		(29 "B.CrtYd" user "B.Courtyard")
		(35 "F.Fab" user)
		(33 "B.Fab" user)
	)
	(footprint "antmicro-footprints:R_0402_1005Metric"
		(layer "B.Cu")
		(at 114.95 69.86 -90)
		(descr "Resistor SMD 0402")
		(tags "resistor SMD 0402")
		(property "Reference" "R139"
			(at 0.8 -0.45 90)
			(layer "B.SilkS")
			(effects
				(font
					(size 0.7 0.7)
					(thickness 0.15)
				)
				(justify left bottom mirror)
			)
		)
		(property "Value" "R_220R_0402"
			(at -1.011843 -1.772047 90)
			(layer "B.Fab")
			(effects
				(font
					(size 0.7 0.7)
					(thickness 0.15)
				)
				(justify left bottom mirror)
			)
		)
		(property "Datasheet" "https://www.bourns.com/docs/product-datasheets/cr.pdf"
			(at 0 0 270)
			(layer "F.Fab")
			(hide yes)
			(effects
				(font
					(size 1.27 1.27)
					(thickness 0.15)
				)
			)
		)
		(property "Author" "Antmicro"
			(at 45.09 184.81 0)
			(layer "B.Fab")
			(hide yes)
			(effects
				(font
					(size 1 1)
					(thickness 0.15)
				)
				(justify mirror)
			)
		)
		(property "License" "Apache-2.0"
			(at 45.09 184.81 0)
			(layer "B.Fab")
			(hide yes)
			(effects
				(font
					(size 1 1)
					(thickness 0.15)
				)
				(justify mirror)
			)
		)
		(property "MPN" "CR0402-FX-2200GLF"
			(at 45.09 184.81 0)
			(layer "B.Fab")
			(hide yes)
			(effects
				(font
					(size 1 1)
					(thickness 0.15)
				)
				(justify mirror)
			)
		)
		(property "Manufacturer" "Bourns"
			(at 45.09 184.81 0)
			(layer "B.Fab")
			(hide yes)
			(effects
				(font
					(size 1 1)
					(thickness 0.15)
				)
				(justify mirror)
			)
		)
		(property "Public" "False"
			(at 45.09 184.81 0)
			(layer "B.Fab")
			(hide yes)
			(effects
				(font
					(size 1 1)
					(thickness 0.15)
				)
				(justify mirror)
			)
		)
		(property "Tolerance" "1%"
			(at 45.09 184.81 0)
			(layer "B.Fab")
			(hide yes)
			(effects
				(font
					(size 1 1)
					(thickness 0.15)
				)
				(justify mirror)
			)
		)
		(property "Val" "220R"
			(at 45.09 184.81 0)
			(layer "B.Fab")
			(hide yes)
			(effects
				(font
					(size 1 1)
					(thickness 0.15)
				)
				(justify mirror)
			)
		)
		(sheetname "M.2 key E")
		(sheetfile "m2keye.kicad_sch")
		(attr smd)
		(fp_rect
			(start -0.925 0.47)
			(end 0.925 -0.47)
			(stroke
				(width 0.05)
				(type default)
			)
			(fill no)
			(layer "B.CrtYd")
		)
		(fp_rect
			(start -0.5 0.25)
			(end 0.5 -0.25)
			(stroke
				(width 0.15)
				(type solid)
			)
			(fill no)
			(layer "B.Fab")
		)
		(pad "1" smd roundrect
			(at -0.48 0 270)
			(size 0.59 0.64)
			(layers "B.Cu" "B.Mask" "B.Paste")
			(roundrect_rratio 0.25)
			(net 938 "Net-(D16-A)")
			(pintype "passive")
			(teardrops
				(best_length_ratio 0.2)
				(max_length 1)
				(best_width_ratio 0.9)
				(max_width 2)
				(curved_edges yes)
				(filter_ratio 0.9)
				(enabled yes)
				(allow_two_segments yes)
				(prefer_zone_connections yes)
			)
		)
		(pad "2" smd roundrect
			(at 0.48 0 270)
			(size 0.59 0.64)
			(layers "B.Cu" "B.Mask" "B.Paste")
			(roundrect_rratio 0.25)
			(net 2 "+3V3")
			(pintype "passive")
			(teardrops
				(best_length_ratio 0.2)
				(max_length 1)
				(best_width_ratio 0.9)
				(max_width 2)
				(curved_edges yes)
				(filter_ratio 0.9)
				(enabled yes)
				(allow_two_segments yes)
				(prefer_zone_connections yes)
			)
		)
	)
	(footprint "antmicro-footprints:TP_SMD_0.75mm"
		(layer "B.Cu")
		(at 208.8 155.95 180)
		(property "Reference" "TP42"
			(at 0.8 -0.4 0)
			(layer "B.SilkS")
			(effects
				(font
					(size 0.7 0.7)
					(thickness 0.15)
				)
				(justify left bottom mirror)
			)
		)
		(property "Value" "TP_0.75mm_SMD"
			(at 3.225 -53.865 0)
			(layer "B.Fab")
			(hide yes)
			(effects
				(font
					(size 0.7 0.7)
					(thickness 0.15)
				)
				(justify left bottom mirror)
			)
		)
		(property "Author" "Antmicro"
			(at 395.05 321.57 0)
			(layer "B.Fab")
			(hide yes)
			(effects
				(font
					(size 1 1)
					(thickness 0.15)
				)
				(justify mirror)
			)
		)
		(property "License" "Apache-2.0"
			(at 395.05 321.57 0)
			(layer "B.Fab")
			(hide yes)
			(effects
				(font
					(size 1 1)
					(thickness 0.15)
				)
				(justify mirror)
			)
		)
		(property "MPN" ""
			(at 395.05 321.57 0)
			(layer "B.Fab")
			(hide yes)
			(effects
				(font
					(size 1 1)
					(thickness 0.15)
				)
				(justify mirror)
			)
		)
		(property "Manufacturer" ""
			(at 395.05 321.57 0)
			(layer "B.Fab")
			(hide yes)
			(effects
				(font
					(size 1 1)
					(thickness 0.15)
				)
				(justify mirror)
			)
		)
		(property "Public" "False"
			(at 395.05 321.57 0)
			(layer "B.Fab")
			(hide yes)
			(effects
				(font
					(size 1 1)
					(thickness 0.15)
				)
				(justify mirror)
			)
		)
		(sheetname "Com Express 7 MGMT")
		(sheetfile "com_express_7_mgmt.kicad_sch")
		(attr exclude_from_pos_files exclude_from_bom)
		(fp_circle
			(center 0 0)
			(end 0.475 0)
			(stroke
				(width 0.05)
				(type default)
			)
			(fill no)
			(layer "B.CrtYd")
		)
		(pad "1" smd circle
			(at 0 0 180)
			(size 0.75 0.75)
			(layers "B.Cu" "B.Mask")
			(net 439 "Net-(J12L-RAPID_SHUTDOWN)")
			(pinfunction "1")
			(pintype "passive")
			(teardrops
				(best_length_ratio 0.4)
				(max_length 1)
				(best_width_ratio 0.9)
				(max_width 2)
				(curved_edges yes)
				(filter_ratio 0.9)
				(enabled yes)
				(allow_two_segments yes)
				(prefer_zone_connections yes)
			)
		)
	)
	(footprint "antmicro-footprints:R_0402_1005Metric"
		(layer "B.Cu")
		(at 99.3 77.81)
		(descr "Resistor SMD 0402")
		(tags "resistor SMD 0402")
		(property "Reference" "R140"
			(at -3.65 0.4 0)
			(layer "B.SilkS")
			(effects
				(font
					(size 0.7 0.7)
					(thickness 0.15)
				)
				(justify right bottom mirror)
			)
		)
		(property "Value" "R_10k_0402"
			(at -1.011843 -1.772047 0)
			(layer "B.Fab")
			(effects
				(font
					(size 0.7 0.7)
					(thickness 0.15)
				)
				(justify right bottom mirror)
			)
		)
		(property "Datasheet" "https://www.bourns.com/docs/product-datasheets/cr.pdf"
			(at 0 0 0)
			(layer "F.Fab")
			(hide yes)
			(effects
				(font
					(size 1.27 1.27)
					(thickness 0.15)
				)
			)
		)
		(property "Description" "SMD Chip Resistor, 10 kohm, ± 1%, 62.5 mW, 0402 [1005 Metric], Thick Film, General Purpose"
			(at 0 0 0)
			(layer "F.Fab")
			(hide yes)
			(effects
				(font
					(size 1.27 1.27)
					(thickness 0.15)
				)
			)
		)
		(property "Author" "Antmicro"
			(at 0 0 0)
			(layer "B.Fab")
			(hide yes)
			(effects
				(font
					(size 1 1)
					(thickness 0.15)
				)
				(justify mirror)
			)
		)
		(property "License" "Apache-2.0"
			(at 0 0 0)
			(layer "B.Fab")
			(hide yes)
			(effects
				(font
					(size 1 1)
					(thickness 0.15)
				)
				(justify mirror)
			)
		)
		(property "MPN" "CR0402-FX-1002GLF"
			(at 0 0 0)
			(layer "B.Fab")
			(hide yes)
			(effects
				(font
					(size 1 1)
					(thickness 0.15)
				)
				(justify mirror)
			)
		)
		(property "Manufacturer" "Bourns"
			(at 0 0 0)
			(layer "B.Fab")
			(hide yes)
			(effects
				(font
					(size 1 1)
					(thickness 0.15)
				)
				(justify mirror)
			)
		)
		(property "Tolerance" "1%"
			(at 0 0 0)
			(layer "B.Fab")
			(hide yes)
			(effects
				(font
					(size 1 1)
					(thickness 0.15)
				)
				(justify mirror)
			)
		)
		(property "Val" "10k"
			(at 0 0 0)
			(layer "B.Fab")
			(hide yes)
			(effects
				(font
					(size 1 1)
					(thickness 0.15)
				)
				(justify mirror)
			)
		)
		(sheetname "Misc")
		(sheetfile "misc.kicad_sch")
		(attr smd)
		(fp_rect
			(start -0.925 0.47)
			(end 0.925 -0.47)
			(stroke
				(width 0.05)
				(type default)
			)
			(fill no)
			(layer "B.CrtYd")
		)
		(fp_rect
			(start -0.5 0.25)
			(end 0.5 -0.25)
			(stroke
				(width 0.15)
				(type solid)
			)
			(fill no)
			(layer "B.Fab")
		)
		(pad "1" smd roundrect
			(at -0.48 0)
			(size 0.59 0.64)
			(layers "B.Cu" "B.Mask" "B.Paste")
			(roundrect_rratio 0.25)
			(net 943 "/GPIO expander/GPIOEX1")
			(pintype "passive")
			(teardrops
				(best_length_ratio 0.2)
				(max_length 1)
				(best_width_ratio 0.9)
				(max_width 2)
				(curved_edges yes)
				(filter_ratio 0.9)
				(enabled yes)
				(allow_two_segments yes)
				(prefer_zone_connections yes)
			)
		)
		(pad "2" smd roundrect
			(at 0.48 0)
			(size 0.59 0.64)
			(layers "B.Cu" "B.Mask" "B.Paste")
			(roundrect_rratio 0.25)
			(net 131 "Net-(D17-C_{B})")
			(pintype "passive")
			(teardrops
				(best_length_ratio 0.2)
				(max_length 1)
				(best_width_ratio 0.9)
				(max_width 2)
				(curved_edges yes)
				(filter_ratio 0.9)
				(enabled yes)
				(allow_two_segments yes)
				(prefer_zone_connections yes)
			)
		)
	)
	(footprint "antmicro-footprints:TP_SMD_0.75mm"
		(layer "B.Cu")
		(at 186.7 168.7 -90)
		(property "Reference" "TP37"
			(at -0.5 3.15 0)
			(layer "B.SilkS")
			(effects
				(font
					(size 0.7 0.7)
					(thickness 0.15)
				)
				(justify right top mirror)
			)
		)
		(property "Value" "TP_0.75mm_SMD"
			(at 0 -1.2 90)
			(layer "B.Fab")
			(effects
				(font
					(size 0.7 0.7)
					(thickness 0.15)
				)
				(justify left bottom mirror)
			)
		)
		(property "Author" "Antmicro"
			(at 432.2 298.12 90)
			(layer "B.Fab")
			(hide yes)
			(effects
				(font
					(size 1 1)
					(thickness 0.15)
				)
				(justify mirror)
			)
		)
		(property "License" "Apache-2.0"
			(at 432.2 298.12 90)
			(layer "B.Fab")
			(hide yes)
			(effects
				(font
					(size 1 1)
					(thickness 0.15)
				)
				(justify mirror)
			)
		)
		(property "MPN" ""
			(at 432.2 298.12 90)
			(layer "B.Fab")
			(hide yes)
			(effects
				(font
					(size 1 1)
					(thickness 0.15)
				)
				(justify mirror)
			)
		)
		(property "Manufacturer" ""
			(at 432.2 298.12 90)
			(layer "B.Fab")
			(hide yes)
			(effects
				(font
					(size 1 1)
					(thickness 0.15)
				)
				(justify mirror)
			)
		)
		(property "Public" "False"
			(at 432.2 298.12 90)
			(layer "B.Fab")
			(hide yes)
			(effects
				(font
					(size 1 1)
					(thickness 0.15)
				)
				(justify mirror)
			)
		)
		(sheetname "Com Express 7 MGMT")
		(sheetfile "com_express_7_mgmt.kicad_sch")
		(attr exclude_from_pos_files exclude_from_bom)
		(fp_circle
			(center 0 0)
			(end 0.475 0)
			(stroke
				(width 0.05)
				(type default)
			)
			(fill no)
			(layer "B.CrtYd")
		)
		(pad "1" smd circle
			(at 0 0 270)
			(size 0.75 0.75)
			(layers "B.Cu" "B.Mask")
			(net 304 "Net-(J12D-~{BATLOW})")
			(pinfunction "1")
			(pintype "passive")
			(teardrops
				(best_length_ratio 0.4)
				(max_length 1)
				(best_width_ratio 0.9)
				(max_width 2)
				(curved_edges yes)
				(filter_ratio 0.9)
				(enabled yes)
				(allow_two_segments yes)
				(prefer_zone_connections yes)
			)
		)
	)
	(footprint "antmicro-footprints:R_0402_1005Metric"
		(layer "B.Cu")
		(at 123.4 112.81 180)
		(descr "Resistor SMD 0402")
		(tags "resistor SMD 0402")
		(property "Reference" "R4"
			(at -2.35 -0.45 0)
			(layer "B.SilkS")
			(effects
				(font
					(size 0.7 0.7)
					(thickness 0.15)
				)
				(justify left bottom mirror)
			)
		)
		(property "Value" "R_0R_0402"
			(at -1.011843 -1.772047 0)
			(layer "B.Fab")
			(effects
				(font
					(size 0.7 0.7)
					(thickness 0.15)
				)
				(justify left bottom mirror)
			)
		)
		(property "Datasheet" "https://industrial.panasonic.com/cdbs/www-data/pdf/RDA0000/AOA0000C301.pdf"
			(at 0 0 180)
			(layer "F.Fab")
			(hide yes)
			(effects
				(font
					(size 1.27 1.27)
					(thickness 0.15)
				)
			)
		)
		(property "Author" "Antmicro"
			(at 246.8 225.62 0)
			(layer "B.Fab")
			(hide yes)
			(effects
				(font
					(size 1 1)
					(thickness 0.15)
				)
				(justify mirror)
			)
		)
		(property "Current" "1A"
			(at 246.8 225.62 0)
			(layer "B.Fab")
			(hide yes)
			(effects
				(font
					(size 1 1)
					(thickness 0.15)
				)
				(justify mirror)
			)
		)
		(property "License" "Apache-2.0"
			(at 246.8 225.62 0)
			(layer "B.Fab")
			(hide yes)
			(effects
				(font
					(size 1 1)
					(thickness 0.15)
				)
				(justify mirror)
			)
		)
		(property "MPN" "ERJ2GE0R00X"
			(at 246.8 225.62 0)
			(layer "B.Fab")
			(hide yes)
			(effects
				(font
					(size 1 1)
					(thickness 0.15)
				)
				(justify mirror)
			)
		)
		(property "Manufacturer" "Panasonic"
			(at 246.8 225.62 0)
			(layer "B.Fab")
			(hide yes)
			(effects
				(font
					(size 1 1)
					(thickness 0.15)
				)
				(justify mirror)
			)
		)
		(property "Public" "False"
			(at 246.8 225.62 0)
			(layer "B.Fab")
			(hide yes)
			(effects
				(font
					(size 1 1)
					(thickness 0.15)
				)
				(justify mirror)
			)
		)
		(property "Tolerance" ""
			(at 246.8 225.62 0)
			(layer "B.Fab")
			(hide yes)
			(effects
				(font
					(size 1 1)
					(thickness 0.15)
				)
				(justify mirror)
			)
		)
		(property "Val" "0R"
			(at 246.8 225.62 0)
			(layer "B.Fab")
			(hide yes)
			(effects
				(font
					(size 1 1)
					(thickness 0.15)
				)
				(justify mirror)
			)
		)
		(sheetname "2xUSB3.0+RJ45")
		(sheetfile "usb3+rj45.kicad_sch")
		(attr smd dnp)
		(fp_rect
			(start -0.925 0.47)
			(end 0.925 -0.47)
			(stroke
				(width 0.05)
				(type default)
			)
			(fill no)
			(layer "B.CrtYd")
		)
		(fp_rect
			(start -0.5 0.25)
			(end 0.5 -0.25)
			(stroke
				(width 0.15)
				(type solid)
			)
			(fill no)
			(layer "B.Fab")
		)
		(pad "1" smd roundrect
			(at -0.48 0 180)
			(size 0.59 0.64)
			(layers "B.Cu" "B.Mask" "B.Paste")
			(roundrect_rratio 0.25)
			(net 291 "/2xUSB3.0+RJ45/~{GBE0_LINK}")
			(pintype "passive")
			(teardrops
				(best_length_ratio 0.2)
				(max_length 1)
				(best_width_ratio 0.9)
				(max_width 2)
				(curved_edges yes)
				(filter_ratio 0.9)
				(enabled yes)
				(allow_two_segments yes)
				(prefer_zone_connections yes)
			)
		)
		(pad "2" smd roundrect
			(at 0.48 0 180)
			(size 0.59 0.64)
			(layers "B.Cu" "B.Mask" "B.Paste")
			(roundrect_rratio 0.25)
			(net 157 "Net-(J1A-LED_D4)")
			(pintype "passive")
			(teardrops
				(best_length_ratio 0.2)
				(max_length 1)
				(best_width_ratio 0.9)
				(max_width 2)
				(curved_edges yes)
				(filter_ratio 0.9)
				(enabled yes)
				(allow_two_segments yes)
				(prefer_zone_connections yes)
			)
		)
	)
	(footprint "antmicro-footprints:C_0603_1608Metric"
		(layer "B.Cu")
		(at 154.6 132.06 -90)
		(descr "Capacitor SMD 0603")
		(tags "capacitor 0603")
		(property "Reference" "C155"
			(at -1.42757 -1.55 90)
			(layer "B.SilkS")
			(effects
				(font
					(size 0.7 0.7)
					(thickness 0.15)
				)
				(justify left bottom mirror)
			)
		)
		(property "Value" "C_22u_16V_0603"
			(at -1.42757 -1.770288 90)
			(layer "B.Fab")
			(effects
				(font
					(size 0.7 0.7)
					(thickness 0.15)
				)
				(justify left bottom mirror)
			)
		)
		(property "Datasheet" "https://product.samsungsem.com/mlcc/CL10A226MO7JZN.do"
			(at 0 0 270)
			(layer "F.Fab")
			(hide yes)
			(effects
				(font
					(size 1.27 1.27)
					(thickness 0.15)
				)
			)
		)
		(property "Author" "Antmicro"
			(at 22.54 286.66 0)
			(layer "B.Fab")
			(hide yes)
			(effects
				(font
					(size 1 1)
					(thickness 0.15)
				)
				(justify mirror)
			)
		)
		(property "Dielectric" ""
			(at 22.54 286.66 0)
			(layer "B.Fab")
			(hide yes)
			(effects
				(font
					(size 1 1)
					(thickness 0.15)
				)
				(justify mirror)
			)
		)
		(property "License" "Apache-2.0"
			(at 22.54 286.66 0)
			(layer "B.Fab")
			(hide yes)
			(effects
				(font
					(size 1 1)
					(thickness 0.15)
				)
				(justify mirror)
			)
		)
		(property "MPN" "CL10A226MO7JZNC"
			(at 22.54 286.66 0)
			(layer "B.Fab")
			(hide yes)
			(effects
				(font
					(size 1 1)
					(thickness 0.15)
				)
				(justify mirror)
			)
		)
		(property "Manufacturer" "Samsung Electro-Mechanics"
			(at 22.54 286.66 0)
			(layer "B.Fab")
			(hide yes)
			(effects
				(font
					(size 1 1)
					(thickness 0.15)
				)
				(justify mirror)
			)
		)
		(property "Public" "False"
			(at 22.54 286.66 0)
			(layer "B.Fab")
			(hide yes)
			(effects
				(font
					(size 1 1)
					(thickness 0.15)
				)
				(justify mirror)
			)
		)
		(property "Val" "22u"
			(at 22.54 286.66 0)
			(layer "B.Fab")
			(hide yes)
			(effects
				(font
					(size 1 1)
					(thickness 0.15)
				)
				(justify mirror)
			)
		)
		(property "Voltage" "16V"
			(at 22.54 286.66 0)
			(layer "B.Fab")
			(hide yes)
			(effects
				(font
					(size 1 1)
					(thickness 0.15)
				)
				(justify mirror)
			)
		)
		(sheetname "KR to SFI #1")
		(sheetfile "kr_sfi.kicad_sch")
		(attr smd)
		(fp_line
			(start 0.15 0.4)
			(end -0.15 0.4)
			(stroke
				(width 0.15)
				(type solid)
			)
			(layer "B.SilkS")
		)
		(fp_line
			(start 0.15 -0.4)
			(end -0.15 -0.4)
			(stroke
				(width 0.15)
				(type solid)
			)
			(layer "B.SilkS")
		)
		(fp_rect
			(start -1.25 0.65)
			(end 1.25 -0.65)
			(stroke
				(width 0.05)
				(type solid)
			)
			(fill no)
			(layer "B.CrtYd")
		)
		(fp_rect
			(start -0.8 0.4)
			(end 0.8 -0.4)
			(stroke
				(width 0.15)
				(type solid)
			)
			(fill no)
			(layer "B.Fab")
		)
		(pad "1" smd roundrect
			(at -0.7 0 270)
			(size 0.8 1)
			(layers "B.Cu" "B.Mask" "B.Paste")
			(roundrect_rratio 0.2)
			(net 1 "GND")
			(pintype "passive")
			(teardrops
				(best_length_ratio 0.2)
				(max_length 1)
				(best_width_ratio 0.9)
				(max_width 2)
				(curved_edges yes)
				(filter_ratio 0.9)
				(enabled yes)
				(allow_two_segments yes)
				(prefer_zone_connections yes)
			)
		)
		(pad "2" smd roundrect
			(at 0.7 0 270)
			(size 0.8 1)
			(layers "B.Cu" "B.Mask" "B.Paste")
			(roundrect_rratio 0.2)
			(net 74 "+1V0")
			(pintype "passive")
			(teardrops
				(best_length_ratio 0.2)
				(max_length 1)
				(best_width_ratio 0.9)
				(max_width 2)
				(curved_edges yes)
				(filter_ratio 0.9)
				(enabled yes)
				(allow_two_segments yes)
				(prefer_zone_connections yes)
			)
		)
	)
)
